(kicad_pcb
	(version 20260206)
	(generator "pcbnew")
	(generator_version "10.0")
	(general
		(thickness 1.6)
		(legacy_teardrops no)
	)
	(paper "A4")
	(title_block
		(title "03242023_DA0F0TMBIJ0_F0T_Motherboard_J_brd_V01_OCP.brd")
		(comment 1 "Grand Teton / footprints 5052-5058 of 6105")
	)
	(layers
		(0 "F.Cu" signal "TOP")
		(4 "In1.Cu" signal "GND")
		(6 "In2.Cu" signal "IN1")
		(8 "In3.Cu" signal "GND1")
		(10 "In4.Cu" signal "IN2")
		(12 "In5.Cu" signal "GND2")
		(14 "In6.Cu" signal "IN3")
		(16 "In7.Cu" signal "GND3")
		(18 "In8.Cu" signal "VCC")
		(20 "In9.Cu" signal "VCC1")
		(22 "In10.Cu" signal "GND4")
		(24 "In11.Cu" signal "IN4")
		(26 "In12.Cu" signal "GND5")
		(28 "In13.Cu" signal "IN5")
		(30 "In14.Cu" signal "GND6")
		(32 "In15.Cu" signal "IN6")
		(34 "In16.Cu" signal "GND7")
		(2 "B.Cu" signal "BOTTOM")
		(9 "F.Adhes" user "F.Adhesive")
		(11 "B.Adhes" user "B.Adhesive")
		(13 "F.Paste" user "Package Geometry/Pastemask Top")
		(15 "B.Paste" user "Package Geometry/Pastemask Bottom")
		(5 "F.SilkS" user "Ref Des/Silkscreen Top")
		(7 "B.SilkS" user "Ref Des/Silkscreen Bottom")
		(1 "F.Mask" user "Board Geometry/Soldermask Top")
		(3 "B.Mask" user "Board Geometry/Soldermask Bottom")
		(17 "Dwgs.User" user "User.Drawings")
		(19 "Cmts.User" user "User.Comments")
		(21 "Eco1.User" user "User.Eco1")
		(23 "Eco2.User" user "User.Eco2")
		(25 "Edge.Cuts" user "Board Geometry/Outline")
		(27 "Margin" user)
		(31 "F.CrtYd" user "Package Geometry/Place Bound Top")
		(29 "B.CrtYd" user "Package Geometry/Place Bound Bottom")
		(35 "F.Fab" user "Ref Des/Assembly Top")
		(33 "B.Fab" user "Ref Des/Assembly Bottom")
	)
	(footprint ""
		(layer "B.Cu")
		(at 416.121342 -354.903786 -90)
		(property "Reference" "PC2645"
			(at 0 0 90)
			(layer "B.SilkS")
			(hide yes)
			(effects
				(font
					(size 1.27 1.27)
				)
				(justify mirror)
			)
		)
		(property "Value" ""
			(at 0 0 90)
			(layer "B.Fab")
			(effects
				(font
					(size 1.27 1.27)
				)
				(justify mirror)
			)
		)
		(duplicate_pad_numbers_are_jumpers no)
		(fp_line
			(start -4.533392 2.249932)
			(end 4.533392 2.249932)
			(stroke
				(width 0.1524)
				(type default)
			)
			(layer "B.SilkS")
		)
		(fp_line
			(start 4.533392 2.249932)
			(end 4.533392 -2.249932)
			(stroke
				(width 0.1524)
				(type default)
			)
			(layer "B.SilkS")
		)
		(fp_line
			(start -4.533392 -2.249932)
			(end -4.533392 2.249932)
			(stroke
				(width 0.1524)
				(type default)
			)
			(layer "B.SilkS")
		)
		(fp_line
			(start 4.533392 -2.249932)
			(end -4.533392 -2.249932)
			(stroke
				(width 0.1524)
				(type default)
			)
			(layer "B.SilkS")
		)
		(fp_rect
			(start 5.39242 2.326132)
			(end 4.533392 -2.326132)
			(stroke
				(width 0)
				(type default)
			)
			(fill yes)
			(layer "B.SilkS")
		)
		(fp_line
			(start -3.750056 2.249932)
			(end 3.750056 2.249932)
			(stroke
				(width 0.1)
				(type default)
			)
			(layer "B.Fab")
		)
		(fp_line
			(start 3.750056 2.249932)
			(end 3.750056 -2.249932)
			(stroke
				(width 0.1)
				(type default)
			)
			(layer "B.Fab")
		)
		(fp_line
			(start -3.750056 -2.249932)
			(end -3.750056 2.249932)
			(stroke
				(width 0.1)
				(type default)
			)
			(layer "B.Fab")
		)
		(fp_line
			(start 3.750056 -2.249932)
			(end -3.750056 -2.249932)
			(stroke
				(width 0.1)
				(type default)
			)
			(layer "B.Fab")
		)
		(fp_text user "-"
			(at -4.598162 1.848612 270)
			(unlocked yes)
			(layer "B.SilkS")
			(effects
				(font
					(size 1.905 1.4224)
					(thickness 0.1524)
				)
				(justify left mirror)
			)
		)
		(fp_text user "+"
			(at 6.322314 0.786384 180)
			(unlocked yes)
			(layer "B.SilkS")
			(effects
				(font
					(size 1.905 1.4224)
					(thickness 0.1524)
				)
				(justify left mirror)
			)
		)
		(fp_text user "+"
			(at 6.322314 0.786384 180)
			(unlocked yes)
			(layer "B.Fab")
			(effects
				(font
					(size 1.905 1.4224)
					(thickness 0.1524)
				)
				(justify left mirror)
			)
		)
		(fp_text user "-"
			(at -4.8514 -0.14605 270)
			(unlocked yes)
			(layer "B.Fab")
			(effects
				(font
					(size 1.905 1.4224)
					(thickness 0.1524)
				)
				(justify left mirror)
			)
		)
		(pad "1" smd rect
			(at 3.199892 0 90)
			(size 2.413 2.8194)
			(layers "B.Cu" "B.Mask" "B.Paste")
			(net "PVCCFA_EHV_FIVRA_CPU0")
		)
		(pad "2" smd rect
			(at -3.199892 0 90)
			(size 2.413 2.8194)
			(layers "B.Cu" "B.Mask" "B.Paste")
			(net "GND")
		)
	)
	(footprint ""
		(layer "B.Cu")
		(at 366.09782 -212.049614)
		(property "Reference" "C525"
			(at 0 0 0)
			(layer "B.SilkS")
			(hide yes)
			(effects
				(font
					(size 1.27 1.27)
				)
				(justify mirror)
			)
		)
		(property "Value" ""
			(at 0 0 0)
			(layer "B.Fab")
			(effects
				(font
					(size 1.27 1.27)
				)
				(justify mirror)
			)
		)
		(duplicate_pad_numbers_are_jumpers no)
		(fp_line
			(start -1.524 -0.762)
			(end -1.524 0.762)
			(stroke
				(width 0.1524)
				(type default)
			)
			(layer "B.SilkS")
		)
		(fp_line
			(start -1.524 0.762)
			(end 1.524 0.762)
			(stroke
				(width 0.1524)
				(type default)
			)
			(layer "B.SilkS")
		)
		(fp_line
			(start 1.524 -0.762)
			(end -1.524 -0.762)
			(stroke
				(width 0.1524)
				(type default)
			)
			(layer "B.SilkS")
		)
		(fp_line
			(start 1.524 0.762)
			(end 1.524 -0.762)
			(stroke
				(width 0.1524)
				(type default)
			)
			(layer "B.SilkS")
		)
		(fp_line
			(start -1.1049 -0.724916)
			(end 1.1049 -0.724916)
			(stroke
				(width 0.1)
				(type default)
			)
			(layer "B.Fab")
		)
		(fp_line
			(start -1.1049 0.724916)
			(end -1.1049 -0.724916)
			(stroke
				(width 0.1)
				(type default)
			)
			(layer "B.Fab")
		)
		(fp_line
			(start 1.1049 -0.724916)
			(end 1.1049 0.724916)
			(stroke
				(width 0.1)
				(type default)
			)
			(layer "B.Fab")
		)
		(fp_line
			(start 1.1049 0.724916)
			(end -1.1049 0.724916)
			(stroke
				(width 0.1)
				(type default)
			)
			(layer "B.Fab")
		)
		(pad "1" smd rect
			(at 0.889 0)
			(size 1.016 1.27)
			(layers "B.Cu" "B.Mask" "B.Paste")
			(net "PVCCINFAON_CPU0")
		)
		(pad "2" smd rect
			(at -0.889 0)
			(size 1.016 1.27)
			(layers "B.Cu" "B.Mask" "B.Paste")
			(net "GND")
		)
	)
	(footprint ""
		(layer "B.Cu")
		(at 376.618754 -190.703708 90)
		(property "Reference" "R689"
			(at 0 0 90)
			(layer "B.SilkS")
			(hide yes)
			(effects
				(font
					(size 1.27 1.27)
				)
				(justify mirror)
			)
		)
		(property "Value" ""
			(at 0 0 90)
			(layer "B.Fab")
			(effects
				(font
					(size 1.27 1.27)
				)
				(justify mirror)
			)
		)
		(duplicate_pad_numbers_are_jumpers no)
		(fp_line
			(start 0.7874 -0.4064)
			(end -0.7874 -0.4064)
			(stroke
				(width 0.1524)
				(type default)
			)
			(layer "B.SilkS")
		)
		(fp_line
			(start -0.7874 -0.4064)
			(end -0.7874 0.4064)
			(stroke
				(width 0.1524)
				(type default)
			)
			(layer "B.SilkS")
		)
		(fp_line
			(start 0.7874 0.4064)
			(end 0.7874 -0.4064)
			(stroke
				(width 0.1524)
				(type default)
			)
			(layer "B.SilkS")
		)
		(fp_line
			(start -0.7874 0.4064)
			(end 0.7874 0.4064)
			(stroke
				(width 0.1524)
				(type default)
			)
			(layer "B.SilkS")
		)
		(fp_line
			(start 0.67945 -0.305054)
			(end 0.12065 -0.305054)
			(stroke
				(width 0.1)
				(type default)
			)
			(layer "B.Fab")
		)
		(fp_line
			(start 0.12065 -0.305054)
			(end 0.12065 -0.2794)
			(stroke
				(width 0.1)
				(type default)
			)
			(layer "B.Fab")
		)
		(fp_line
			(start -0.12065 -0.3048)
			(end -0.67945 -0.3048)
			(stroke
				(width 0.1)
				(type default)
			)
			(layer "B.Fab")
		)
		(fp_line
			(start -0.67945 -0.3048)
			(end -0.67945 0.3048)
			(stroke
				(width 0.1)
				(type default)
			)
			(layer "B.Fab")
		)
		(fp_line
			(start 0.12065 -0.2794)
			(end -0.12065 -0.2794)
			(stroke
				(width 0.1)
				(type default)
			)
			(layer "B.Fab")
		)
		(fp_line
			(start -0.12065 -0.2794)
			(end -0.12065 -0.3048)
			(stroke
				(width 0.1)
				(type default)
			)
			(layer "B.Fab")
		)
		(fp_line
			(start 0.12065 0.2794)
			(end 0.12065 0.3048)
			(stroke
				(width 0.1)
				(type default)
			)
			(layer "B.Fab")
		)
		(fp_line
			(start -0.120396 0.2794)
			(end 0.12065 0.2794)
			(stroke
				(width 0.1)
				(type default)
			)
			(layer "B.Fab")
		)
		(fp_line
			(start 0.67945 0.3048)
			(end 0.67945 -0.305054)
			(stroke
				(width 0.1)
				(type default)
			)
			(layer "B.Fab")
		)
		(fp_line
			(start 0.12065 0.3048)
			(end 0.67945 0.3048)
			(stroke
				(width 0.1)
				(type default)
			)
			(layer "B.Fab")
		)
		(fp_line
			(start -0.120396 0.3048)
			(end -0.120396 0.2794)
			(stroke
				(width 0.1)
				(type default)
			)
			(layer "B.Fab")
		)
		(fp_line
			(start -0.67945 0.3048)
			(end -0.120396 0.3048)
			(stroke
				(width 0.1)
				(type default)
			)
			(layer "B.Fab")
		)
		(pad "1" smd circle
			(at 0.40005 0 270)
			(size 0 0)
			(layers "B.Cu" "B.Mask" "B.Paste")
			(net "I3C_SPD_DDREFGH_CPU0_SCL")
		)
		(pad "2" smd circle
			(at -0.40005 0 270)
			(size 0 0)
			(layers "B.Cu" "B.Mask" "B.Paste")
			(net "I3C_SPD_DDREFGH_CPU0_R_SCL")
		)
	)
	(footprint ""
		(layer "B.Cu")
		(at 339.042756 -50.678842 90)
		(property "Reference" "C1262"
			(at 0 0 90)
			(layer "B.SilkS")
			(hide yes)
			(effects
				(font
					(size 1.27 1.27)
				)
				(justify mirror)
			)
		)
		(property "Value" ""
			(at 0 0 90)
			(layer "B.Fab")
			(effects
				(font
					(size 1.27 1.27)
				)
				(justify mirror)
			)
		)
		(duplicate_pad_numbers_are_jumpers no)
		(fp_line
			(start 0.7874 -0.4064)
			(end -0.7874 -0.4064)
			(stroke
				(width 0.1524)
				(type default)
			)
			(layer "B.SilkS")
		)
		(fp_line
			(start -0.7874 -0.4064)
			(end -0.7874 0.4064)
			(stroke
				(width 0.1524)
				(type default)
			)
			(layer "B.SilkS")
		)
		(fp_line
			(start 0.7874 0.4064)
			(end 0.7874 -0.4064)
			(stroke
				(width 0.1524)
				(type default)
			)
			(layer "B.SilkS")
		)
		(fp_line
			(start -0.7874 0.4064)
			(end 0.7874 0.4064)
			(stroke
				(width 0.1524)
				(type default)
			)
			(layer "B.SilkS")
		)
		(fp_line
			(start 0.67945 -0.305054)
			(end 0.12065 -0.305054)
			(stroke
				(width 0.1)
				(type default)
			)
			(layer "B.Fab")
		)
		(fp_line
			(start 0.12065 -0.305054)
			(end 0.12065 -0.2794)
			(stroke
				(width 0.1)
				(type default)
			)
			(layer "B.Fab")
		)
		(fp_line
			(start -0.12065 -0.3048)
			(end -0.67945 -0.3048)
			(stroke
				(width 0.1)
				(type default)
			)
			(layer "B.Fab")
		)
		(fp_line
			(start -0.67945 -0.3048)
			(end -0.67945 0.3048)
			(stroke
				(width 0.1)
				(type default)
			)
			(layer "B.Fab")
		)
		(fp_line
			(start 0.12065 -0.2794)
			(end -0.12065 -0.2794)
			(stroke
				(width 0.1)
				(type default)
			)
			(layer "B.Fab")
		)
		(fp_line
			(start -0.12065 -0.2794)
			(end -0.12065 -0.3048)
			(stroke
				(width 0.1)
				(type default)
			)
			(layer "B.Fab")
		)
		(fp_line
			(start 0.12065 0.2794)
			(end 0.12065 0.3048)
			(stroke
				(width 0.1)
				(type default)
			)
			(layer "B.Fab")
		)
		(fp_line
			(start -0.120396 0.2794)
			(end 0.12065 0.2794)
			(stroke
				(width 0.1)
				(type default)
			)
			(layer "B.Fab")
		)
		(fp_line
			(start 0.67945 0.3048)
			(end 0.67945 -0.305054)
			(stroke
				(width 0.1)
				(type default)
			)
			(layer "B.Fab")
		)
		(fp_line
			(start 0.12065 0.3048)
			(end 0.67945 0.3048)
			(stroke
				(width 0.1)
				(type default)
			)
			(layer "B.Fab")
		)
		(fp_line
			(start -0.120396 0.3048)
			(end -0.120396 0.2794)
			(stroke
				(width 0.1)
				(type default)
			)
			(layer "B.Fab")
		)
		(fp_line
			(start -0.67945 0.3048)
			(end -0.120396 0.3048)
			(stroke
				(width 0.1)
				(type default)
			)
			(layer "B.Fab")
		)
		(pad "1" smd circle
			(at 0.40005 0 270)
			(size 0 0)
			(layers "B.Cu" "B.Mask" "B.Paste")
			(net "P1V05_PCH_PLL_AUX")
		)
		(pad "2" smd circle
			(at -0.40005 0 270)
			(size 0 0)
			(layers "B.Cu" "B.Mask" "B.Paste")
			(net "GND")
		)
	)
	(footprint ""
		(layer "B.Cu")
		(at 409.32608 -148.173948 180)
		(property "Reference" "PR4229"
			(at 0 0 0)
			(layer "B.SilkS")
			(hide yes)
			(effects
				(font
					(size 1.27 1.27)
				)
				(justify mirror)
			)
		)
		(property "Value" ""
			(at 0 0 0)
			(layer "B.Fab")
			(effects
				(font
					(size 1.27 1.27)
				)
				(justify mirror)
			)
		)
		(duplicate_pad_numbers_are_jumpers no)
		(fp_line
			(start 0.7874 0.4064)
			(end 0.7874 -0.4064)
			(stroke
				(width 0.1524)
				(type default)
			)
			(layer "B.SilkS")
		)
		(fp_line
			(start 0.7874 -0.4064)
			(end -0.7874 -0.4064)
			(stroke
				(width 0.1524)
				(type default)
			)
			(layer "B.SilkS")
		)
		(fp_line
			(start -0.7874 0.4064)
			(end 0.7874 0.4064)
			(stroke
				(width 0.1524)
				(type default)
			)
			(layer "B.SilkS")
		)
		(fp_line
			(start -0.7874 -0.4064)
			(end -0.7874 0.4064)
			(stroke
				(width 0.1524)
				(type default)
			)
			(layer "B.SilkS")
		)
		(fp_line
			(start 0.67945 0.3048)
			(end 0.67945 -0.305054)
			(stroke
				(width 0.1)
				(type default)
			)
			(layer "B.Fab")
		)
		(fp_line
			(start 0.67945 -0.305054)
			(end 0.12065 -0.305054)
			(stroke
				(width 0.1)
				(type default)
			)
			(layer "B.Fab")
		)
		(fp_line
			(start 0.12065 0.3048)
			(end 0.67945 0.3048)
			(stroke
				(width 0.1)
				(type default)
			)
			(layer "B.Fab")
		)
		(fp_line
			(start 0.12065 0.2794)
			(end 0.12065 0.3048)
			(stroke
				(width 0.1)
				(type default)
			)
			(layer "B.Fab")
		)
		(fp_line
			(start 0.12065 -0.2794)
			(end -0.12065 -0.2794)
			(stroke
				(width 0.1)
				(type default)
			)
			(layer "B.Fab")
		)
		(fp_line
			(start 0.12065 -0.305054)
			(end 0.12065 -0.2794)
			(stroke
				(width 0.1)
				(type default)
			)
			(layer "B.Fab")
		)
		(fp_line
			(start -0.120396 0.3048)
			(end -0.120396 0.2794)
			(stroke
				(width 0.1)
				(type default)
			)
			(layer "B.Fab")
		)
		(fp_line
			(start -0.120396 0.2794)
			(end 0.12065 0.2794)
			(stroke
				(width 0.1)
				(type default)
			)
			(layer "B.Fab")
		)
		(fp_line
			(start -0.12065 -0.2794)
			(end -0.12065 -0.3048)
			(stroke
				(width 0.1)
				(type default)
			)
			(layer "B.Fab")
		)
		(fp_line
			(start -0.12065 -0.3048)
			(end -0.67945 -0.3048)
			(stroke
				(width 0.1)
				(type default)
			)
			(layer "B.Fab")
		)
		(fp_line
			(start -0.67945 0.3048)
			(end -0.120396 0.3048)
			(stroke
				(width 0.1)
				(type default)
			)
			(layer "B.Fab")
		)
		(fp_line
			(start -0.67945 -0.3048)
			(end -0.67945 0.3048)
			(stroke
				(width 0.1)
				(type default)
			)
			(layer "B.Fab")
		)
		(pad "1" smd circle
			(at 0.40005 0)
			(size 0 0)
			(layers "B.Cu" "B.Mask" "B.Paste")
			(net "PVCCFA_EHV_CPU0")
		)
		(pad "2" smd circle
			(at -0.40005 0)
			(size 0 0)
			(layers "B.Cu" "B.Mask" "B.Paste")
			(net "GND")
		)
	)
	(footprint ""
		(layer "B.Cu")
		(at 333.382366 -328.298048 -90)
		(property "Reference" "PC268_P0_6"
			(at 0 0 90)
			(layer "B.SilkS")
			(hide yes)
			(effects
				(font
					(size 1.27 1.27)
				)
				(justify mirror)
			)
		)
		(property "Value" ""
			(at 0 0 90)
			(layer "B.Fab")
			(effects
				(font
					(size 1.27 1.27)
				)
				(justify mirror)
			)
		)
		(duplicate_pad_numbers_are_jumpers no)
		(fp_line
			(start -1.524 0.762)
			(end 1.524 0.762)
			(stroke
				(width 0.1524)
				(type default)
			)
			(layer "B.SilkS")
		)
		(fp_line
			(start 1.524 0.762)
			(end 1.524 -0.762)
			(stroke
				(width 0.1524)
				(type default)
			)
			(layer "B.SilkS")
		)
		(fp_line
			(start -1.524 -0.762)
			(end -1.524 0.762)
			(stroke
				(width 0.1524)
				(type default)
			)
			(layer "B.SilkS")
		)
		(fp_line
			(start 1.524 -0.762)
			(end -1.524 -0.762)
			(stroke
				(width 0.1524)
				(type default)
			)
			(layer "B.SilkS")
		)
		(fp_line
			(start -1.1049 0.724916)
			(end -1.1049 -0.724916)
			(stroke
				(width 0.1)
				(type default)
			)
			(layer "B.Fab")
		)
		(fp_line
			(start 1.1049 0.724916)
			(end -1.1049 0.724916)
			(stroke
				(width 0.1)
				(type default)
			)
			(layer "B.Fab")
		)
		(fp_line
			(start -1.1049 -0.724916)
			(end 1.1049 -0.724916)
			(stroke
				(width 0.1)
				(type default)
			)
			(layer "B.Fab")
		)
		(fp_line
			(start 1.1049 -0.724916)
			(end 1.1049 0.724916)
			(stroke
				(width 0.1)
				(type default)
			)
			(layer "B.Fab")
		)
		(pad "1" smd rect
			(at 0.889 0 270)
			(size 1.016 1.27)
			(layers "B.Cu" "B.Mask" "B.Paste")
			(net "PVCCIN_CPU0")
		)
		(pad "2" smd rect
			(at -0.889 0 270)
			(size 1.016 1.27)
			(layers "B.Cu" "B.Mask" "B.Paste")
			(net "GND")
		)
	)
	(footprint ""
		(layer "B.Cu")
		(at 186.464194 -319.028826 90)
		(property "Reference" "R946"
			(at 0 0 90)
			(layer "B.SilkS")
			(hide yes)
			(effects
				(font
					(size 1.27 1.27)
				)
				(justify mirror)
			)
		)
		(property "Value" ""
			(at 0 0 90)
			(layer "B.Fab")
			(effects
				(font
					(size 1.27 1.27)
				)
				(justify mirror)
			)
		)
		(duplicate_pad_numbers_are_jumpers no)
		(fp_line
			(start 0.7874 -0.4064)
			(end -0.7874 -0.4064)
			(stroke
				(width 0.1524)
				(type default)
			)
			(layer "B.SilkS")
		)
		(fp_line
			(start -0.7874 -0.4064)
			(end -0.7874 0.4064)
			(stroke
				(width 0.1524)
				(type default)
			)
			(layer "B.SilkS")
		)
		(fp_line
			(start 0.7874 0.4064)
			(end 0.7874 -0.4064)
			(stroke
				(width 0.1524)
				(type default)
			)
			(layer "B.SilkS")
		)
		(fp_line
			(start -0.7874 0.4064)
			(end 0.7874 0.4064)
			(stroke
				(width 0.1524)
				(type default)
			)
			(layer "B.SilkS")
		)
		(fp_line
			(start 0.67945 -0.305054)
			(end 0.12065 -0.305054)
			(stroke
				(width 0.1)
				(type default)
			)
			(layer "B.Fab")
		)
		(fp_line
			(start 0.12065 -0.305054)
			(end 0.12065 -0.2794)
			(stroke
				(width 0.1)
				(type default)
			)
			(layer "B.Fab")
		)
		(fp_line
			(start -0.12065 -0.3048)
			(end -0.67945 -0.3048)
			(stroke
				(width 0.1)
				(type default)
			)
			(layer "B.Fab")
		)
		(fp_line
			(start -0.67945 -0.3048)
			(end -0.67945 0.3048)
			(stroke
				(width 0.1)
				(type default)
			)
			(layer "B.Fab")
		)
		(fp_line
			(start 0.12065 -0.2794)
			(end -0.12065 -0.2794)
			(stroke
				(width 0.1)
				(type default)
			)
			(layer "B.Fab")
		)
		(fp_line
			(start -0.12065 -0.2794)
			(end -0.12065 -0.3048)
			(stroke
				(width 0.1)
				(type default)
			)
			(layer "B.Fab")
		)
		(fp_line
			(start 0.12065 0.2794)
			(end 0.12065 0.3048)
			(stroke
				(width 0.1)
				(type default)
			)
			(layer "B.Fab")
		)
		(fp_line
			(start -0.120396 0.2794)
			(end 0.12065 0.2794)
			(stroke
				(width 0.1)
				(type default)
			)
			(layer "B.Fab")
		)
		(fp_line
			(start 0.67945 0.3048)
			(end 0.67945 -0.305054)
			(stroke
				(width 0.1)
				(type default)
			)
			(layer "B.Fab")
		)
		(fp_line
			(start 0.12065 0.3048)
			(end 0.67945 0.3048)
			(stroke
				(width 0.1)
				(type default)
			)
			(layer "B.Fab")
		)
		(fp_line
			(start -0.120396 0.3048)
			(end -0.120396 0.2794)
			(stroke
				(width 0.1)
				(type default)
			)
			(layer "B.Fab")
		)
		(fp_line
			(start -0.67945 0.3048)
			(end -0.120396 0.3048)
			(stroke
				(width 0.1)
				(type default)
			)
			(layer "B.Fab")
		)
		(pad "1" smd circle
			(at 0.40005 0 270)
			(size 0 0)
			(layers "B.Cu" "B.Mask" "B.Paste")
			(net "P3V3_AUX")
		)
		(pad "2" smd circle
			(at -0.40005 0 270)
			(size 0 0)
			(layers "B.Cu" "B.Mask" "B.Paste")
			(net "PWRGD_FAIL_CPU1_EF_R1")
		)
	)
)
